(kicad_pcb
	(version 20260206)
	(generator "pcbnew")
	(generator_version "10.0")
	(general
		(thickness 1.6)
		(legacy_teardrops no)
	)
	(paper "A4")
	(title_block
		(title "fcb — 12433-1M.1206WZS1330.brd")
		(comment 1 "Open Vault / Knox (Wiwynn) / footprints 321-325 of 495")
	)
	(layers
		(0 "F.Cu" signal "TOP")
		(4 "In1.Cu" signal "L2GND")
		(6 "In2.Cu" signal "L3VCC")
		(2 "B.Cu" signal "BOTTOM")
		(9 "F.Adhes" user "F.Adhesive")
		(11 "B.Adhes" user "B.Adhesive")
		(13 "F.Paste" user "Package Geometry/Pastemask Top")
		(15 "B.Paste" user "Package Geometry/Pastemask Bottom")
		(5 "F.SilkS" user "Ref Des/Silkscreen Top")
		(7 "B.SilkS" user "Ref Des/Silkscreen Bottom")
		(1 "F.Mask" user "Board Geometry/Soldermask Top")
		(3 "B.Mask" user "Board Geometry/Soldermask Bottom")
		(17 "Dwgs.User" user "User.Drawings")
		(19 "Cmts.User" user "User.Comments")
		(21 "Eco1.User" user "User.Eco1")
		(23 "Eco2.User" user "User.Eco2")
		(25 "Edge.Cuts" user "Board Geometry/Outline")
		(27 "Margin" user)
		(31 "F.CrtYd" user "Package Geometry/Place Bound Top")
		(29 "B.CrtYd" user "Package Geometry/Place Bound Bottom")
		(35 "F.Fab" user "Ref Des/Assembly Top")
		(33 "B.Fab" user "Ref Des/Assembly Bottom")
	)
	(footprint ""
		(layer "F.Cu")
		(at 4.040124 -482.700076 -90)
		(property "Reference" "CN1"
			(at 0 0 270)
			(layer "F.SilkS")
			(hide yes)
			(effects
				(font
					(size 1.27 1.27)
				)
			)
		)
		(property "Value" "JWT-CON5-42-GP"
			(at -7.8105 2.9591 270)
			(unlocked yes)
			(layer "F.Fab")
			(hide yes)
			(effects
				(font
					(size 1.016 1.016)
					(thickness 0.1524)
				)
			)
		)
		(property "Device Type" "A2541WR0-1TX5PA-6T-0E"
			(at -7.8105 1.4351 270)
			(unlocked yes)
			(layer "F.Fab")
			(hide yes)
			(effects
				(font
					(size 1.016 1.016)
					(thickness 0.1524)
				)
			)
		)
		(duplicate_pad_numbers_are_jumpers no)
		(fp_line
			(start -6.604 10.287)
			(end 6.604 10.287)
			(stroke
				(width 0.1524)
				(type default)
			)
			(layer "F.SilkS")
		)
		(fp_line
			(start 6.604 10.287)
			(end 6.604 -0.9652)
			(stroke
				(width 0.1524)
				(type default)
			)
			(layer "F.SilkS")
		)
		(fp_line
			(start -6.604 -0.9652)
			(end -6.604 10.287)
			(stroke
				(width 0.1524)
				(type default)
			)
			(layer "F.SilkS")
		)
		(fp_line
			(start 6.604 -0.9652)
			(end -6.604 -0.9652)
			(stroke
				(width 0.1524)
				(type default)
			)
			(layer "F.SilkS")
		)
		(fp_line
			(start -6.731 -1.0922)
			(end -6.731 0.1778)
			(stroke
				(width 0.4064)
				(type default)
			)
			(layer "F.SilkS")
		)
		(fp_line
			(start -5.461 -1.0922)
			(end -6.731 -1.0922)
			(stroke
				(width 0.4064)
				(type default)
			)
			(layer "F.SilkS")
		)
		(fp_circle
			(center -5.08 0)
			(end -5.08 -1.0668)
			(stroke
				(width 0.3048)
				(type default)
			)
			(fill no)
			(layer "F.SilkS")
		)
		(fp_circle
			(center -2.54 0)
			(end -2.54 -1.0668)
			(stroke
				(width 0.3048)
				(type default)
			)
			(fill no)
			(layer "F.SilkS")
		)
		(fp_circle
			(center 0 0)
			(end 0 -1.0668)
			(stroke
				(width 0.3048)
				(type default)
			)
			(fill no)
			(layer "F.SilkS")
		)
		(fp_circle
			(center 2.54 0)
			(end 2.54 -1.0668)
			(stroke
				(width 0.3048)
				(type default)
			)
			(fill no)
			(layer "F.SilkS")
		)
		(fp_circle
			(center 5.08 0)
			(end 5.08 -1.0668)
			(stroke
				(width 0.3048)
				(type default)
			)
			(fill no)
			(layer "F.SilkS")
		)
		(fp_rect
			(start -6.35 10.033)
			(end 6.35 -0.3302)
			(stroke
				(width 0)
				(type default)
			)
			(fill no)
			(layer "F.CrtYd")
		)
		(fp_poly
			(pts
				(xy -6.35 -0.3302) (xy 6.858 -0.3302) (xy 6.858 -1.2192) (xy -6.858 -1.2192) (xy -6.858 10.541)
				(xy 6.858 10.541) (xy 6.858 -0.3175) (xy 6.35 -0.3175) (xy 6.35 10.033) (xy -6.35 10.033)
			)
			(stroke
				(width 0)
				(type default)
			)
			(fill no)
			(layer "F.CrtYd")
		)
		(fp_rect
			(start -6.858 10.541)
			(end 6.858 -1.2192)
			(stroke
				(width 0)
				(type default)
			)
			(fill no)
			(layer "F.Fab")
		)
		(pad "1" thru_hole circle
			(at -5.08 0 270)
			(size 1.4224 1.4224)
			(drill 1.016)
			(layers "*.Cu" "*.Mask")
			(remove_unused_layers no)
			(net "GND")
			(clearance 0.1524)
			(thermal_gap 0.1524)
		)
		(pad "2" thru_hole circle
			(at -2.54 0 270)
			(size 1.4224 1.4224)
			(drill 1.016)
			(layers "*.Cu" "*.Mask")
			(remove_unused_layers no)
			(net "P12V_FAN1")
			(clearance 0.1524)
			(thermal_gap 0.1524)
		)
		(pad "3" thru_hole circle
			(at 0 0 270)
			(size 1.4224 1.4224)
			(drill 1.016)
			(layers "*.Cu" "*.Mask")
			(remove_unused_layers no)
			(net "FAN_TACH2")
			(clearance 0.1524)
			(thermal_gap 0.1524)
		)
		(pad "4" thru_hole circle
			(at 2.54 0 270)
			(size 1.4224 1.4224)
			(drill 1.016)
			(layers "*.Cu" "*.Mask")
			(remove_unused_layers no)
			(net "PWM_OUT_FAN1_NET")
			(clearance 0.1524)
			(thermal_gap 0.1524)
		)
		(pad "5" thru_hole circle
			(at 5.08 0 270)
			(size 1.4224 1.4224)
			(drill 1.016)
			(layers "*.Cu" "*.Mask")
			(remove_unused_layers no)
			(net "FAN_TACH1")
			(clearance 0.1524)
			(thermal_gap 0.1524)
		)
	)
	(footprint ""
		(layer "F.Cu")
		(at 30.3784 -111.125 90)
		(property "Reference" "PR102"
			(at 0 0 90)
			(layer "F.SilkS")
			(hide yes)
			(effects
				(font
					(size 1.27 1.27)
				)
			)
		)
		(property "Value" "10R2F-L-GP"
			(at 0.064008 -3.993896 90)
			(unlocked yes)
			(layer "F.Fab")
			(hide yes)
			(effects
				(font
					(size 1.016 1.016)
					(thickness 0.1524)
				)
			)
		)
		(property "Device Type" "R402H14"
			(at 0.064008 -5.517896 90)
			(unlocked yes)
			(layer "F.Fab")
			(hide yes)
			(effects
				(font
					(size 1.016 1.016)
					(thickness 0.1524)
				)
			)
		)
		(duplicate_pad_numbers_are_jumpers no)
		(fp_line
			(start 0.508 -0.9398)
			(end -0.508 -0.9398)
			(stroke
				(width 0.1524)
				(type default)
			)
			(layer "F.SilkS")
		)
		(fp_line
			(start -0.508 -0.9398)
			(end -0.508 0.9398)
			(stroke
				(width 0.1524)
				(type default)
			)
			(layer "F.SilkS")
		)
		(fp_rect
			(start -0.508 0.9398)
			(end 0.508 -0.9398)
			(stroke
				(width 0)
				(type default)
			)
			(fill no)
			(layer "F.CrtYd")
		)
		(fp_rect
			(start -0.508 0.9398)
			(end 0.508 -0.9398)
			(stroke
				(width 0)
				(type default)
			)
			(fill no)
			(layer "F.Fab")
		)
		(pad "1" smd custom
			(at 0 -0.4445 90)
			(size 0.1397 0.1397)
			(layers "F.Cu" "F.Mask" "F.Paste")
			(net "P12VU_2490_GATE_DRV")
			(options
				(clearance outline)
				(anchor circle)
			)
			(primitives
				(gr_poly
					(pts
						(arc
							(start -0.1778 -0.2794)
							(mid -0.249642 -0.249642)
							(end -0.2794 -0.1778)
						)
						(arc
							(start -0.2794 0.1778)
							(mid -0.249642 0.249642)
							(end -0.1778 0.2794)
						)
						(arc
							(start 0.1778 0.2794)
							(mid 0.249642 0.249642)
							(end 0.2794 0.1778)
						)
						(arc
							(start 0.2794 -0.1778)
							(mid 0.249642 -0.249642)
							(end 0.1778 -0.2794)
						)
					)
					(width 0)
					(fill yes)
				)
			)
		)
		(pad "2" smd custom
			(at 0 0.4445 90)
			(size 0.1397 0.1397)
			(layers "F.Cu" "F.Mask" "F.Paste")
			(net "P12VU_2490_GATE")
			(options
				(clearance outline)
				(anchor circle)
			)
			(primitives
				(gr_poly
					(pts
						(arc
							(start -0.1778 -0.2794)
							(mid -0.249642 -0.249642)
							(end -0.2794 -0.1778)
						)
						(arc
							(start -0.2794 0.1778)
							(mid -0.249642 0.249642)
							(end -0.1778 0.2794)
						)
						(arc
							(start 0.1778 0.2794)
							(mid 0.249642 0.249642)
							(end 0.2794 0.1778)
						)
						(arc
							(start 0.2794 -0.1778)
							(mid 0.249642 -0.249642)
							(end 0.1778 -0.2794)
						)
					)
					(width 0)
					(fill yes)
				)
			)
		)
	)
	(footprint ""
		(layer "F.Cu")
		(at 33.909 -374.396)
		(property "Reference" "PC6"
			(at 0 0 0)
			(layer "F.SilkS")
			(hide yes)
			(effects
				(font
					(size 1.27 1.27)
				)
			)
		)
		(property "Value" "SCD022U50V3KX-2-GP"
			(at 0 -2.8194 0)
			(unlocked yes)
			(layer "F.Fab")
			(hide yes)
			(effects
				(font
					(size 1.016 1.016)
					(thickness 0.1524)
				)
			)
		)
		(property "Device Type" "C603"
			(at 0 -4.3434 0)
			(unlocked yes)
			(layer "F.Fab")
			(hide yes)
			(effects
				(font
					(size 1.016 1.016)
					(thickness 0.1524)
				)
			)
		)
		(duplicate_pad_numbers_are_jumpers no)
		(fp_line
			(start 0.508 0)
			(end -0.508 0)
			(stroke
				(width 0.2032)
				(type default)
			)
			(layer "F.SilkS")
		)
		(fp_rect
			(start -0.5842 1.3335)
			(end 0.5842 -1.3335)
			(stroke
				(width 0)
				(type default)
			)
			(fill no)
			(layer "F.CrtYd")
		)
		(fp_rect
			(start -0.5842 1.3335)
			(end 0.5842 -1.3335)
			(stroke
				(width 0)
				(type default)
			)
			(fill no)
			(layer "F.Fab")
		)
		(pad "1" smd custom
			(at 0 -0.762)
			(size 0.2159 0.2159)
			(layers "F.Cu" "F.Mask" "F.Paste")
			(net "ADM1276_GATE_RC")
			(options
				(clearance outline)
				(anchor circle)
			)
			(primitives
				(gr_poly
					(pts
						(arc
							(start -0.3302 -0.4318)
							(mid -0.402042 -0.402042)
							(end -0.4318 -0.3302)
						)
						(arc
							(start -0.4318 0.3302)
							(mid -0.402042 0.402042)
							(end -0.3302 0.4318)
						)
						(arc
							(start 0.3302 0.4318)
							(mid 0.402042 0.402042)
							(end 0.4318 0.3302)
						)
						(arc
							(start 0.4318 -0.3302)
							(mid 0.402042 -0.402042)
							(end 0.3302 -0.4318)
						)
					)
					(width 0)
					(fill yes)
				)
			)
		)
		(pad "2" smd custom
			(at 0 0.762)
			(size 0.2159 0.2159)
			(layers "F.Cu" "F.Mask" "F.Paste")
			(net "GND")
			(options
				(clearance outline)
				(anchor circle)
			)
			(primitives
				(gr_poly
					(pts
						(arc
							(start -0.3302 -0.4318)
							(mid -0.402042 -0.402042)
							(end -0.4318 -0.3302)
						)
						(arc
							(start -0.4318 0.3302)
							(mid -0.402042 0.402042)
							(end -0.3302 0.4318)
						)
						(arc
							(start 0.3302 0.4318)
							(mid 0.402042 0.402042)
							(end 0.4318 0.3302)
						)
						(arc
							(start 0.4318 -0.3302)
							(mid 0.402042 -0.402042)
							(end 0.3302 -0.4318)
						)
					)
					(width 0)
					(fill yes)
				)
			)
		)
	)
	(footprint ""
		(layer "F.Cu")
		(at 7.8232 -449.5546 90)
		(property "Reference" "R100"
			(at 0 0 90)
			(layer "F.SilkS")
			(hide yes)
			(effects
				(font
					(size 1.27 1.27)
				)
			)
		)
		(property "Value" "27KR3F-GP"
			(at -0.0254 -2.5146 90)
			(unlocked yes)
			(layer "F.Fab")
			(hide yes)
			(effects
				(font
					(size 1.016 1.016)
					(thickness 0.1524)
				)
			)
		)
		(property "Device Type" "R603H22"
			(at -0.0254 -4.0386 90)
			(unlocked yes)
			(layer "F.Fab")
			(hide yes)
			(effects
				(font
					(size 1.016 1.016)
					(thickness 0.1524)
				)
			)
		)
		(duplicate_pad_numbers_are_jumpers no)
		(fp_line
			(start 0.2032 0)
			(end 0.4826 0)
			(stroke
				(width 0.2032)
				(type default)
			)
			(layer "F.SilkS")
		)
		(fp_line
			(start -0.4826 0)
			(end -0.2032 0)
			(stroke
				(width 0.2032)
				(type default)
			)
			(layer "F.SilkS")
		)
		(fp_rect
			(start -0.5842 1.3335)
			(end 0.5842 -1.3335)
			(stroke
				(width 0)
				(type default)
			)
			(fill no)
			(layer "F.CrtYd")
		)
		(fp_rect
			(start -0.5842 1.3335)
			(end 0.5842 -1.3335)
			(stroke
				(width 0)
				(type default)
			)
			(fill no)
			(layer "F.Fab")
		)
		(pad "1" smd custom
			(at 0 -0.762 90)
			(size 0.2159 0.2159)
			(layers "F.Cu" "F.Mask" "F.Paste")
			(net "FANIN_1")
			(options
				(clearance outline)
				(anchor circle)
			)
			(primitives
				(gr_poly
					(pts
						(arc
							(start -0.3302 -0.4318)
							(mid -0.402042 -0.402042)
							(end -0.4318 -0.3302)
						)
						(arc
							(start -0.4318 0.3302)
							(mid -0.402042 0.402042)
							(end -0.3302 0.4318)
						)
						(arc
							(start 0.3302 0.4318)
							(mid 0.402042 0.402042)
							(end 0.4318 0.3302)
						)
						(arc
							(start 0.4318 -0.3302)
							(mid 0.402042 -0.402042)
							(end 0.3302 -0.4318)
						)
					)
					(width 0)
					(fill yes)
				)
			)
		)
		(pad "2" smd custom
			(at 0 0.762 90)
			(size 0.2159 0.2159)
			(layers "F.Cu" "F.Mask" "F.Paste")
			(net "FAN_TACH1")
			(options
				(clearance outline)
				(anchor circle)
			)
			(primitives
				(gr_poly
					(pts
						(arc
							(start -0.3302 -0.4318)
							(mid -0.402042 -0.402042)
							(end -0.4318 -0.3302)
						)
						(arc
							(start -0.4318 0.3302)
							(mid -0.402042 0.402042)
							(end -0.3302 0.4318)
						)
						(arc
							(start 0.3302 0.4318)
							(mid 0.402042 0.402042)
							(end 0.4318 0.3302)
						)
						(arc
							(start 0.4318 -0.3302)
							(mid 0.402042 -0.402042)
							(end 0.3302 -0.4318)
						)
					)
					(width 0)
					(fill yes)
				)
			)
		)
	)
	(footprint ""
		(layer "F.Cu")
		(at 21.766784 -214.4014 90)
		(property "Reference" "R130"
			(at 0 0 90)
			(layer "F.SilkS")
			(hide yes)
			(effects
				(font
					(size 1.27 1.27)
				)
			)
		)
		(property "Value" "4K7R2F-GP"
			(at 0.064008 -3.993896 90)
			(unlocked yes)
			(layer "F.Fab")
			(hide yes)
			(effects
				(font
					(size 1.016 1.016)
					(thickness 0.1524)
				)
			)
		)
		(property "Device Type" "R402H16"
			(at 0.064008 -5.517896 90)
			(unlocked yes)
			(layer "F.Fab")
			(hide yes)
			(effects
				(font
					(size 1.016 1.016)
					(thickness 0.1524)
				)
			)
		)
		(duplicate_pad_numbers_are_jumpers no)
		(fp_line
			(start 0.508 -0.9398)
			(end -0.508 -0.9398)
			(stroke
				(width 0.1524)
				(type default)
			)
			(layer "F.SilkS")
		)
		(fp_line
			(start -0.508 -0.9398)
			(end -0.508 0.9398)
			(stroke
				(width 0.1524)
				(type default)
			)
			(layer "F.SilkS")
		)
		(fp_rect
			(start -0.508 0.9398)
			(end 0.508 -0.9398)
			(stroke
				(width 0)
				(type default)
			)
			(fill no)
			(layer "F.CrtYd")
		)
		(fp_rect
			(start -0.508 0.9398)
			(end 0.508 -0.9398)
			(stroke
				(width 0)
				(type default)
			)
			(fill no)
			(layer "F.Fab")
		)
		(pad "1" smd custom
			(at 0 -0.4445 90)
			(size 0.1397 0.1397)
			(layers "F.Cu" "F.Mask" "F.Paste")
			(net "P3V3")
			(options
				(clearance outline)
				(anchor circle)
			)
			(primitives
				(gr_poly
					(pts
						(arc
							(start -0.1778 -0.2794)
							(mid -0.249642 -0.249642)
							(end -0.2794 -0.1778)
						)
						(arc
							(start -0.2794 0.1778)
							(mid -0.249642 0.249642)
							(end -0.1778 0.2794)
						)
						(arc
							(start 0.1778 0.2794)
							(mid 0.249642 0.249642)
							(end 0.2794 0.1778)
						)
						(arc
							(start 0.2794 -0.1778)
							(mid 0.249642 -0.249642)
							(end 0.1778 -0.2794)
						)
					)
					(width 0)
					(fill yes)
				)
			)
		)
		(pad "2" smd custom
			(at 0 0.4445 90)
			(size 0.1397 0.1397)
			(layers "F.Cu" "F.Mask" "F.Paste")
			(net "PWM_OUT_FAN6")
			(options
				(clearance outline)
				(anchor circle)
			)
			(primitives
				(gr_poly
					(pts
						(arc
							(start -0.1778 -0.2794)
							(mid -0.249642 -0.249642)
							(end -0.2794 -0.1778)
						)
						(arc
							(start -0.2794 0.1778)
							(mid -0.249642 0.249642)
							(end -0.1778 0.2794)
						)
						(arc
							(start 0.1778 0.2794)
							(mid 0.249642 0.249642)
							(end 0.2794 0.1778)
						)
						(arc
							(start 0.2794 -0.1778)
							(mid 0.249642 -0.249642)
							(end 0.1778 -0.2794)
						)
					)
					(width 0)
					(fill yes)
				)
			)
		)
	)
)
